# BASEBOARD_FAB2 (Tioga Pass) — schematic netlist excerpt (pin names and nets, part order shuffled) for the footprints in the layout excerpt that follows; sources: Cadence DE-HDL packaged netlist, KiCad conversion of Wiwynn_Tioga_Pass_MB.brd

C5L10  CAP_A  47UF 4V 20% X5R  pkg 0603V  page 220 : A = PVDDQ_DEF ; B = GND
C9N27  CAP  10UF 16V 10% X6S  pkg 0805  page 209 : A = VR_FET_SW_P12V_STBY_PVCCIN_CPU1 ; B = GND
C9P2  CAP  10UF 16V 10% X6S  pkg 0805  page 208 : A = VR_FET_SW_P12V_STBY_PVCCIN_CPU1 ; B = GND

(kicad_pcb
	(version 20260206)
	(generator "pcbnew")
	(generator_version "10.0")
	(general
		(thickness 1.6)
		(legacy_teardrops no)
	)
	(paper "A4")
	(title_block
		(title "Wiwynn_Tioga_Pass_MB.brd")
		(comment 1 "Tioga Pass / footprints 3561-3563 of 4770")
	)
	(layers
		(0 "F.Cu" signal "TOP")
		(4 "In1.Cu" signal "L2GND")
		(6 "In2.Cu" signal "L3")
		(8 "In3.Cu" signal "L4GND")
		(10 "In4.Cu" signal "L5")
		(12 "In5.Cu" signal "L6GND")
		(14 "In6.Cu" signal "L7VCC")
		(16 "In7.Cu" signal "L8VCC")
		(18 "In8.Cu" signal "L9GND")
		(20 "In9.Cu" signal "L10")
		(22 "In10.Cu" signal "L11GND")
		(24 "In11.Cu" signal "L12")
		(26 "In12.Cu" signal "L13GND")
		(2 "B.Cu" signal "BOTTOM")
		(9 "F.Adhes" user "F.Adhesive")
		(11 "B.Adhes" user "B.Adhesive")
		(13 "F.Paste" user "Package Geometry/Pastemask Top")
		(15 "B.Paste" user "Package Geometry/Pastemask Bottom")
		(5 "F.SilkS" user "Ref Des/Silkscreen Top")
		(7 "B.SilkS" user "Ref Des/Silkscreen Bottom")
		(1 "F.Mask" user "Board Geometry/Soldermask Top")
		(3 "B.Mask" user "Board Geometry/Soldermask Bottom")
		(17 "Dwgs.User" user "User.Drawings")
		(19 "Cmts.User" user "User.Comments")
		(21 "Eco1.User" user "User.Eco1")
		(23 "Eco2.User" user "User.Eco2")
		(25 "Edge.Cuts" user "Board Geometry/Outline")
		(27 "Margin" user)
		(31 "F.CrtYd" user "Package Geometry/Place Bound Top")
		(29 "B.CrtYd" user "Package Geometry/Place Bound Bottom")
		(35 "F.Fab" user "Ref Des/Assembly Top")
		(33 "B.Fab" user "Ref Des/Assembly Bottom")
	)
	(footprint ""
		(layer "B.Cu")
		(at 32.832802 -89.158064 90)
		(property "Reference" "C9N27"
			(at 0 0 90)
			(layer "B.SilkS")
			(hide yes)
			(effects
				(font
					(size 1.27 1.27)
				)
				(justify mirror)
			)
		)
		(property "Value" ""
			(at 0 0 90)
			(layer "B.Fab")
			(effects
				(font
					(size 1.27 1.27)
				)
				(justify mirror)
			)
		)
		(duplicate_pad_numbers_are_jumpers no)
		(fp_poly
			(pts
				(xy 0.7239 -0.2159) (xy -0.7239 -0.2159) (xy -0.7239 1.9939) (xy 0.7239 1.9939)
			)
			(stroke
				(width 0)
				(type default)
			)
			(fill no)
			(layer "B.CrtYd")
		)
		(fp_line
			(start 0.7239 -0.2159)
			(end 0.7239 1.9939)
			(stroke
				(width 0.1)
				(type default)
			)
			(layer "B.Fab")
		)
		(fp_line
			(start -0.7239 -0.2159)
			(end 0.7239 -0.2159)
			(stroke
				(width 0.1)
				(type default)
			)
			(layer "B.Fab")
		)
		(fp_line
			(start 0.7239 1.9939)
			(end -0.7239 1.9939)
			(stroke
				(width 0.1)
				(type default)
			)
			(layer "B.Fab")
		)
		(fp_line
			(start -0.7239 1.9939)
			(end -0.7239 -0.2159)
			(stroke
				(width 0.1)
				(type default)
			)
			(layer "B.Fab")
		)
		(pad "1" smd rect
			(at 0 0 270)
			(size 1.27 1.016)
			(layers "B.Cu" "B.Mask" "B.Paste")
			(net "VR_FET_SW_P12V_STBY_PVCCIN_CPU1")
		)
		(pad "2" smd rect
			(at 0 1.778 270)
			(size 1.27 1.016)
			(layers "B.Cu" "B.Mask" "B.Paste")
			(net "GND")
		)
		(zone
			(layer "B.Cu")
			(hatch none 0.5)
			(connect_pads
				(clearance 0)
			)
			(min_thickness 0.25)
			(keepout
				(tracks not_allowed)
				(vias allowed)
				(pads allowed)
				(copperpour not_allowed)
				(footprints allowed)
			)
			(placement
				(enabled no)
				(sheetname "")
			)
			(fill
				(thermal_gap 0.5)
				(thermal_bridge_width 0.5)
				(island_removal_mode 0)
			)
			(polygon
				(pts
					(xy 33.340802 -89.793064) (xy 33.340802 -88.523064) (xy 34.102802 -88.523064) (xy 34.102802 -89.793064)
				)
			)
		)
	)
	(footprint ""
		(layer "B.Cu")
		(at 253.392432 -145.0086 90)
		(property "Reference" "C5L10"
			(at -1.848866 0.752348 90)
			(unlocked yes)
			(layer "B.SilkS")
			(effects
				(font
					(size 1.27 0.9652)
					(thickness 0.1524)
				)
				(justify mirror)
			)
		)
		(property "Value" ""
			(at 0 0 90)
			(layer "B.Fab")
			(effects
				(font
					(size 1.27 1.27)
				)
				(justify mirror)
			)
		)
		(duplicate_pad_numbers_are_jumpers no)
		(fp_rect
			(start 0.500126 1.598422)
			(end -0.500126 -0.201422)
			(stroke
				(width 0)
				(type default)
			)
			(fill no)
			(layer "B.CrtYd")
		)
		(fp_line
			(start 0.500126 -0.201422)
			(end -0.500126 -0.201422)
			(stroke
				(width 0.1)
				(type default)
			)
			(layer "B.Fab")
		)
		(fp_line
			(start -0.500126 -0.201422)
			(end -0.500126 1.598422)
			(stroke
				(width 0.1)
				(type default)
			)
			(layer "B.Fab")
		)
		(fp_line
			(start 0.500126 1.598422)
			(end 0.500126 -0.201422)
			(stroke
				(width 0.1)
				(type default)
			)
			(layer "B.Fab")
		)
		(fp_line
			(start -0.500126 1.598422)
			(end 0.500126 1.598422)
			(stroke
				(width 0.1)
				(type default)
			)
			(layer "B.Fab")
		)
		(pad "1" smd rect
			(at 0 0)
			(size 0.889 0.9906)
			(layers "B.Cu" "B.Mask" "B.Paste")
			(net "PVDDQ_DEF")
		)
		(pad "2" smd rect
			(at 0 1.397)
			(size 0.889 0.9906)
			(layers "B.Cu" "B.Mask" "B.Paste")
			(net "GND")
		)
		(zone
			(layer "B.Cu")
			(hatch none 0.5)
			(connect_pads
				(clearance 0)
			)
			(min_thickness 0.25)
			(keepout
				(tracks not_allowed)
				(vias allowed)
				(pads allowed)
				(copperpour not_allowed)
				(footprints allowed)
			)
			(placement
				(enabled no)
				(sheetname "")
			)
			(fill
				(thermal_gap 0.5)
				(thermal_bridge_width 0.5)
				(island_removal_mode 0)
			)
			(polygon
				(pts
					(xy 254.344932 -145.5039) (xy 253.836932 -145.5039) (xy 253.836932 -144.5133) (xy 254.344932 -144.5133)
				)
			)
		)
		(zone
			(layer "B.Cu")
			(hatch none 0.5)
			(connect_pads
				(clearance 0)
			)
			(min_thickness 0.25)
			(keepout
				(tracks allowed)
				(vias not_allowed)
				(pads allowed)
				(copperpour not_allowed)
				(footprints allowed)
			)
			(placement
				(enabled no)
				(sheetname "")
			)
			(fill
				(thermal_gap 0.5)
				(thermal_bridge_width 0.5)
				(island_removal_mode 0)
			)
			(polygon
				(pts
					(xy 254.344932 -145.5039) (xy 253.836932 -145.5039) (xy 253.836932 -144.5133) (xy 254.344932 -144.5133)
				)
			)
		)
	)
	(footprint ""
		(layer "B.Cu")
		(at 32.832802 -84.357464 90)
		(property "Reference" "C9P2"
			(at 0 0 90)
			(layer "B.SilkS")
			(hide yes)
			(effects
				(font
					(size 1.27 1.27)
				)
				(justify mirror)
			)
		)
		(property "Value" ""
			(at 0 0 90)
			(layer "B.Fab")
			(effects
				(font
					(size 1.27 1.27)
				)
				(justify mirror)
			)
		)
		(duplicate_pad_numbers_are_jumpers no)
		(fp_poly
			(pts
				(xy 0.7239 -0.2159) (xy -0.7239 -0.2159) (xy -0.7239 1.9939) (xy 0.7239 1.9939)
			)
			(stroke
				(width 0)
				(type default)
			)
			(fill no)
			(layer "B.CrtYd")
		)
		(fp_line
			(start 0.7239 -0.2159)
			(end 0.7239 1.9939)
			(stroke
				(width 0.1)
				(type default)
			)
			(layer "B.Fab")
		)
		(fp_line
			(start -0.7239 -0.2159)
			(end 0.7239 -0.2159)
			(stroke
				(width 0.1)
				(type default)
			)
			(layer "B.Fab")
		)
		(fp_line
			(start 0.7239 1.9939)
			(end -0.7239 1.9939)
			(stroke
				(width 0.1)
				(type default)
			)
			(layer "B.Fab")
		)
		(fp_line
			(start -0.7239 1.9939)
			(end -0.7239 -0.2159)
			(stroke
				(width 0.1)
				(type default)
			)
			(layer "B.Fab")
		)
		(pad "1" smd rect
			(at 0 0 270)
			(size 1.27 1.016)
			(layers "B.Cu" "B.Mask" "B.Paste")
			(net "VR_FET_SW_P12V_STBY_PVCCIN_CPU1")
		)
		(pad "2" smd rect
			(at 0 1.778 270)
			(size 1.27 1.016)
			(layers "B.Cu" "B.Mask" "B.Paste")
			(net "GND")
		)
		(zone
			(layer "B.Cu")
			(hatch none 0.5)
			(connect_pads
				(clearance 0)
			)
			(min_thickness 0.25)
			(keepout
				(tracks not_allowed)
				(vias allowed)
				(pads allowed)
				(copperpour not_allowed)
				(footprints allowed)
			)
			(placement
				(enabled no)
				(sheetname "")
			)
			(fill
				(thermal_gap 0.5)
				(thermal_bridge_width 0.5)
				(island_removal_mode 0)
			)
			(polygon
				(pts
					(xy 33.340802 -84.992464) (xy 33.340802 -83.722464) (xy 34.102802 -83.722464) (xy 34.102802 -84.992464)
				)
			)
		)
	)
)
